FILE_TYPE = MULTI_PHYS_TABLE;
PART 'BATTERY'
CLASS='MECHANICAL'
{==============================================================================================}
:PACK_TYPE | PART_NUMBER      = EnvComp | PART_NUMBER  | DESCRIPTION     |JEDEC_TYPE    | HEIGHT    | COMPONENT_TYPE | LPID  | SPEED_URL | Status |RPL| AML | Bus_Unit | Days ;
{==============================================================================================}
'PLCLF'    | '202168-001'(!)  = 'Excl;Excl;Excl;Excl;ok;Excl' | '202168-001' | 'BATTERY_ONLY'  | 'PLC_HOLDER' | '0.16 IN' | 'PSEUDO'       | '' | 'http://speed.intel.com:8081/speed/module/pdm/item/pdm_item_detail_direct.asp?item_cde=202168-001&item_rev=01&url_param=unused' | 'Approved' | 'YES' | '12' | 'SMO_BOARDS' | '42' 
'PLC'      | '202168-001'(!)  = 'Excl;Excl;Excl;Excl;ok;Excl' | '202168-001' | 'BATTERY_ONLY'  | 'PLC_HOLDER' | '0.16 IN' | 'PSEUDO'       | '' | 'http://speed.intel.com:8081/speed/module/pdm/item/pdm_item_detail_direct.asp?item_cde=202168-001&item_rev=01&url_param=unused' | 'Approved' | 'YES' | '12' | 'SMO_BOARDS' | '42' 
END_PART
END.
